# T6G (Grand Teton) — schematic netlist excerpt (pin names and nets, part order shuffled) for the footprints in the layout excerpt that follows; sources: Cadence DE-HDL packaged netlist, KiCad conversion of 04192023_DAF0TMB3IC0_F0TG_MB_C_brd_V02_OCP.brd

R6731  Q_RES  200 1% CHIP  pkg 0201LF  page 332 : A = RT_CPU1_P1_VQPS ; B = GND
R3705  Q_RES  10K 1% EMPTY  pkg 0402LF  page 252 : A = P3V3_AUX ; B = RST_SMB_SWITCH_N
R1730  Q_RES  4.7K 5% EMPTY  pkg 0402LF  page 171 : A = P3V3_AUX ; B = SCM_JTAG_MUX_S1

(kicad_pcb
	(version 20260206)
	(generator "pcbnew")
	(generator_version "10.0")
	(general
		(thickness 1.6)
		(legacy_teardrops no)
	)
	(paper "A4")
	(title_block
		(title "04192023_DAF0TMB3IC0_F0TG_MB_C_brd_V02_OCP.brd")
		(comment 1 "Grand Teton / footprints 1510-1512 of 8354")
	)
	(layers
		(0 "F.Cu" signal "TOP")
		(4 "In1.Cu" signal "GND")
		(6 "In2.Cu" signal "IN1")
		(8 "In3.Cu" signal "GND1")
		(10 "In4.Cu" signal "IN2")
		(12 "In5.Cu" signal "GND2")
		(14 "In6.Cu" signal "IN3")
		(16 "In7.Cu" signal "GND3")
		(18 "In8.Cu" signal "VCC")
		(20 "In9.Cu" signal "VCC1")
		(22 "In10.Cu" signal "GND4")
		(24 "In11.Cu" signal "IN4")
		(26 "In12.Cu" signal "GND5")
		(28 "In13.Cu" signal "IN5")
		(30 "In14.Cu" signal "GND6")
		(32 "In15.Cu" signal "IN6")
		(34 "In16.Cu" signal "GND7")
		(2 "B.Cu" signal "BOTTOM")
		(9 "F.Adhes" user "F.Adhesive")
		(11 "B.Adhes" user "B.Adhesive")
		(13 "F.Paste" user "Package Geometry/Pastemask Top")
		(15 "B.Paste" user "Package Geometry/Pastemask Bottom")
		(5 "F.SilkS" user "Ref Des/Silkscreen Top")
		(7 "B.SilkS" user "Ref Des/Silkscreen Bottom")
		(1 "F.Mask" user "Board Geometry/Soldermask Top")
		(3 "B.Mask" user "Board Geometry/Soldermask Bottom")
		(17 "Dwgs.User" user "User.Drawings")
		(19 "Cmts.User" user "User.Comments")
		(21 "Eco1.User" user "User.Eco1")
		(23 "Eco2.User" user "User.Eco2")
		(25 "Edge.Cuts" user "Board Geometry/Outline")
		(27 "Margin" user)
		(31 "F.CrtYd" user "Package Geometry/Place Bound Top")
		(29 "B.CrtYd" user "Package Geometry/Place Bound Bottom")
		(35 "F.Fab" user "Ref Des/Assembly Top")
		(33 "B.Fab" user "Ref Des/Assembly Bottom")
	)
	(footprint ""
		(layer "F.Cu")
		(at 254.592836 -124.50445)
		(property "Reference" "R3705"
			(at 0 0 0)
			(layer "F.SilkS")
			(hide yes)
			(effects
				(font
					(size 1.27 1.27)
				)
			)
		)
		(property "Value" ""
			(at 0 0 0)
			(layer "F.Fab")
			(effects
				(font
					(size 1.27 1.27)
				)
			)
		)
		(duplicate_pad_numbers_are_jumpers no)
		(fp_line
			(start -0.7874 -0.4064)
			(end 0.7874 -0.4064)
			(stroke
				(width 0.1524)
				(type default)
			)
			(layer "F.SilkS")
		)
		(fp_line
			(start -0.7874 0.4064)
			(end -0.7874 -0.4064)
			(stroke
				(width 0.1524)
				(type default)
			)
			(layer "F.SilkS")
		)
		(fp_line
			(start 0.7874 -0.4064)
			(end 0.7874 0.4064)
			(stroke
				(width 0.1524)
				(type default)
			)
			(layer "F.SilkS")
		)
		(fp_line
			(start 0.7874 0.4064)
			(end -0.7874 0.4064)
			(stroke
				(width 0.1524)
				(type default)
			)
			(layer "F.SilkS")
		)
		(fp_line
			(start -0.67945 -0.305054)
			(end -0.12065 -0.305054)
			(stroke
				(width 0.1)
				(type default)
			)
			(layer "F.Fab")
		)
		(fp_line
			(start -0.67945 0.3048)
			(end -0.67945 -0.305054)
			(stroke
				(width 0.1)
				(type default)
			)
			(layer "F.Fab")
		)
		(fp_line
			(start -0.12065 -0.305054)
			(end -0.12065 -0.2794)
			(stroke
				(width 0.1)
				(type default)
			)
			(layer "F.Fab")
		)
		(fp_line
			(start -0.12065 -0.2794)
			(end 0.12065 -0.2794)
			(stroke
				(width 0.1)
				(type default)
			)
			(layer "F.Fab")
		)
		(fp_line
			(start -0.12065 0.2794)
			(end -0.12065 0.3048)
			(stroke
				(width 0.1)
				(type default)
			)
			(layer "F.Fab")
		)
		(fp_line
			(start -0.12065 0.3048)
			(end -0.67945 0.3048)
			(stroke
				(width 0.1)
				(type default)
			)
			(layer "F.Fab")
		)
		(fp_line
			(start 0.120396 0.2794)
			(end -0.12065 0.2794)
			(stroke
				(width 0.1)
				(type default)
			)
			(layer "F.Fab")
		)
		(fp_line
			(start 0.120396 0.3048)
			(end 0.120396 0.2794)
			(stroke
				(width 0.1)
				(type default)
			)
			(layer "F.Fab")
		)
		(fp_line
			(start 0.12065 -0.3048)
			(end 0.67945 -0.3048)
			(stroke
				(width 0.1)
				(type default)
			)
			(layer "F.Fab")
		)
		(fp_line
			(start 0.12065 -0.2794)
			(end 0.12065 -0.3048)
			(stroke
				(width 0.1)
				(type default)
			)
			(layer "F.Fab")
		)
		(fp_line
			(start 0.67945 -0.3048)
			(end 0.67945 0.3048)
			(stroke
				(width 0.1)
				(type default)
			)
			(layer "F.Fab")
		)
		(fp_line
			(start 0.67945 0.3048)
			(end 0.120396 0.3048)
			(stroke
				(width 0.1)
				(type default)
			)
			(layer "F.Fab")
		)
		(pad "1" smd circle
			(at -0.40005 0)
			(size 0 0)
			(layers "F.Cu" "F.Mask" "F.Paste")
			(net "P3V3_AUX")
		)
		(pad "2" smd circle
			(at 0.40005 0)
			(size 0 0)
			(layers "F.Cu" "F.Mask" "F.Paste")
			(net "RST_SMB_SWITCH_N")
		)
	)
	(footprint ""
		(layer "F.Cu")
		(at 117.330474 -55.036212 90)
		(property "Reference" "R1730"
			(at 0 0 90)
			(layer "F.SilkS")
			(hide yes)
			(effects
				(font
					(size 1.27 1.27)
				)
			)
		)
		(property "Value" ""
			(at 0 0 90)
			(layer "F.Fab")
			(effects
				(font
					(size 1.27 1.27)
				)
			)
		)
		(duplicate_pad_numbers_are_jumpers no)
		(fp_line
			(start 0.7874 -0.4064)
			(end 0.7874 0.4064)
			(stroke
				(width 0.1524)
				(type default)
			)
			(layer "F.SilkS")
		)
		(fp_line
			(start -0.7874 -0.4064)
			(end 0.7874 -0.4064)
			(stroke
				(width 0.1524)
				(type default)
			)
			(layer "F.SilkS")
		)
		(fp_line
			(start 0.7874 0.4064)
			(end -0.7874 0.4064)
			(stroke
				(width 0.1524)
				(type default)
			)
			(layer "F.SilkS")
		)
		(fp_line
			(start -0.7874 0.4064)
			(end -0.7874 -0.4064)
			(stroke
				(width 0.1524)
				(type default)
			)
			(layer "F.SilkS")
		)
		(fp_line
			(start -0.12065 -0.305054)
			(end -0.12065 -0.2794)
			(stroke
				(width 0.1)
				(type default)
			)
			(layer "F.Fab")
		)
		(fp_line
			(start -0.67945 -0.305054)
			(end -0.12065 -0.305054)
			(stroke
				(width 0.1)
				(type default)
			)
			(layer "F.Fab")
		)
		(fp_line
			(start 0.67945 -0.3048)
			(end 0.67945 0.3048)
			(stroke
				(width 0.1)
				(type default)
			)
			(layer "F.Fab")
		)
		(fp_line
			(start 0.12065 -0.3048)
			(end 0.67945 -0.3048)
			(stroke
				(width 0.1)
				(type default)
			)
			(layer "F.Fab")
		)
		(fp_line
			(start 0.12065 -0.2794)
			(end 0.12065 -0.3048)
			(stroke
				(width 0.1)
				(type default)
			)
			(layer "F.Fab")
		)
		(fp_line
			(start -0.12065 -0.2794)
			(end 0.12065 -0.2794)
			(stroke
				(width 0.1)
				(type default)
			)
			(layer "F.Fab")
		)
		(fp_line
			(start 0.120396 0.2794)
			(end -0.12065 0.2794)
			(stroke
				(width 0.1)
				(type default)
			)
			(layer "F.Fab")
		)
		(fp_line
			(start -0.12065 0.2794)
			(end -0.12065 0.3048)
			(stroke
				(width 0.1)
				(type default)
			)
			(layer "F.Fab")
		)
		(fp_line
			(start 0.67945 0.3048)
			(end 0.120396 0.3048)
			(stroke
				(width 0.1)
				(type default)
			)
			(layer "F.Fab")
		)
		(fp_line
			(start 0.120396 0.3048)
			(end 0.120396 0.2794)
			(stroke
				(width 0.1)
				(type default)
			)
			(layer "F.Fab")
		)
		(fp_line
			(start -0.12065 0.3048)
			(end -0.67945 0.3048)
			(stroke
				(width 0.1)
				(type default)
			)
			(layer "F.Fab")
		)
		(fp_line
			(start -0.67945 0.3048)
			(end -0.67945 -0.305054)
			(stroke
				(width 0.1)
				(type default)
			)
			(layer "F.Fab")
		)
		(pad "1" smd circle
			(at -0.40005 0 90)
			(size 0 0)
			(layers "F.Cu" "F.Mask" "F.Paste")
			(net "P3V3_AUX")
		)
		(pad "2" smd circle
			(at 0.40005 0 90)
			(size 0 0)
			(layers "F.Cu" "F.Mask" "F.Paste")
			(net "SCM_JTAG_MUX_S1")
		)
	)
	(footprint ""
		(layer "F.Cu")
		(at 99.080828 -394.3604 -90)
		(property "Reference" "R6731"
			(at 0 0 270)
			(layer "F.SilkS")
			(hide yes)
			(effects
				(font
					(size 1.27 1.27)
				)
			)
		)
		(property "Value" ""
			(at 0 0 270)
			(layer "F.Fab")
			(effects
				(font
					(size 1.27 1.27)
				)
			)
		)
		(duplicate_pad_numbers_are_jumpers no)
		(fp_line
			(start -0.32512 0.175006)
			(end -0.32512 -0.175006)
			(stroke
				(width 0.1)
				(type default)
			)
			(layer "F.Fab")
		)
		(fp_line
			(start 0.32512 0.175006)
			(end -0.32512 0.175006)
			(stroke
				(width 0.1)
				(type default)
			)
			(layer "F.Fab")
		)
		(fp_line
			(start -0.32512 -0.175006)
			(end 0.32512 -0.175006)
			(stroke
				(width 0.1)
				(type default)
			)
			(layer "F.Fab")
		)
		(fp_line
			(start 0.32512 -0.175006)
			(end 0.32512 0.175006)
			(stroke
				(width 0.1)
				(type default)
			)
			(layer "F.Fab")
		)
		(pad "1" smd rect
			(at -0.2667 0 270)
			(size 0.3048 0.381)
			(layers "F.Cu" "F.Mask" "F.Paste")
			(net "RT_CPU1_P1_VQPS")
		)
		(pad "2" smd rect
			(at 0.2667 0 90)
			(size 0.3048 0.381)
			(layers "F.Cu" "F.Mask" "F.Paste")
			(net "GND")
		)
	)
)
